#ISCELL
  mstr_misc dns *
  *
#ISCELL
  pure_quanta quanta_title_block_c *
  *
#CELL
  pure_quanta 74lvc2g08dp *
  page258_i1
#ISCELL
  standard offpage *
  page258_i10
#CELL
  pure_quanta 74lvc2g08dp *
  page258_i11
#CELL
  pure_quanta 74lvc2g08dp *
  page258_i12
#CELL
  pure_quanta 74lvc2g08dp *
  page258_i13
#CELL
  pure_quanta 74lvc2g08dp *
  page258_i14
#CELL
  pure_quanta nc7sb3157 *
  page258_i15
#CELL
  pure_quanta nc7sb3157 *
  page258_i16
#CELL
  pure_quanta nc7sb3157 *
  page258_i17
#CELL
  pure_quanta nc7sb3157 *
  page258_i18
#ISCELL
  pure_quanta_power universal_gnd *
  page258_i19
#CELL
  pure_quanta 74lvc2g08dp *
  page258_i2
#ISCELL
  pure_quanta_power universal_power *
  page258_i20
#CELL
  pure_quanta q_cap *
  page258_i21
#CELL
  pure_quanta q_cap *
  page258_i22
#ISCELL
  pure_quanta_power universal_power *
  page258_i23
#ISCELL
  pure_quanta_power universal_gnd *
  page258_i24
#ISCELL
  pure_quanta_power universal_gnd *
  page258_i25
#ISCELL
  pure_quanta_power universal_gnd *
  page258_i26
#CELL
  pure_quanta q_cap *
  page258_i27
#ISCELL
  pure_quanta_power universal_gnd *
  page258_i28
#ISCELL
  pure_quanta_power universal_power *
  page258_i29
#ISCELL
  standard offpage *
  page258_i3
#ISCELL
  pure_quanta_power universal_power *
  page258_i30
#CELL
  pure_quanta q_cap *
  page258_i31
#ISCELL
  pure_quanta_power universal_gnd *
  page258_i32
#ISCELL
  pure_quanta_power universal_power *
  page258_i33
#CELL
  pure_quanta q_cap *
  page258_i34
#ISCELL
  pure_quanta_power universal_gnd *
  page258_i35
#ISCELL
  pure_quanta_power universal_gnd *
  page258_i36
#CELL
  pure_quanta q_cap *
  page258_i37
#ISCELL
  pure_quanta_power universal_power *
  page258_i38
#ISCELL
  pure_quanta_power universal_gnd *
  page258_i39
#ISCELL
  standard offpage *
  page258_i4
#ISCELL
  pure_quanta_power universal_power *
  page258_i40
#CELL
  pure_quanta q_cap *
  page258_i41
#ISCELL
  pure_quanta_power universal_gnd *
  page258_i42
#CELL
  pure_quanta q_res *
  page258_i44
#CELL
  pure_quanta q_res *
  page258_i45
#CELL
  pure_quanta q_res *
  page258_i46
#CELL
  pure_quanta q_res *
  page258_i47
#ISCELL
  standard offpage *
  page258_i48
#ISCELL
  standard offpage *
  page258_i49
#ISCELL
  standard offpage *
  page258_i5
#CELL
  pure_quanta q_res *
  page258_i50
#ISCELL
  standard offpage *
  page258_i51
#CELL
  pure_quanta q_res *
  page258_i52
#ISCELL
  standard offpage *
  page258_i53
#ISCELL
  standard offpage *
  page258_i54
#ISCELL
  standard offpage *
  page258_i56
#ISCELL
  standard offpage *
  page258_i58
#ISCELL
  standard offpage *
  page258_i59
#ISCELL
  standard offpage *
  page258_i6
#ISCELL
  pure_quanta_power universal_gnd *
  page258_i60
#ISCELL
  pure_quanta_power universal_gnd *
  page258_i61
#ISCELL
  pure_quanta_power universal_gnd *
  page258_i62
#ISCELL
  pure_quanta_power universal_gnd *
  page258_i63
#CELL
  pure_quanta q_res *
  page258_i64
#CELL
  pure_quanta q_res *
  page258_i65
#CELL
  pure_quanta q_res *
  page258_i66
#CELL
  pure_quanta q_res *
  page258_i67
#CELL
  pure_quanta q_cap *
  page258_i68
#ISCELL
  pure_quanta_power universal_gnd *
  page258_i69
#ISCELL
  standard offpage *
  page258_i7
#CELL
  pure_quanta q_cap *
  page258_i70
#ISCELL
  pure_quanta_power universal_gnd *
  page258_i71
#CELL
  pure_quanta q_cap *
  page258_i72
#ISCELL
  pure_quanta_power universal_gnd *
  page258_i73
#CELL
  pure_quanta q_cap *
  page258_i74
#ISCELL
  pure_quanta_power universal_gnd *
  page258_i75
#ISCELL
  standard offpage *
  page258_i8
#ISCELL
  standard offpage *
  page258_i9
